# HDMI-MIPI Bridge — KiCad project settings (.kicad_pro: net classes, design rules, text variables)
{
  "board": {
    "3dviewports": [],
    "design_settings": {
      "defaults": {
        "board_outline_line_width": 0.09999999999999999,
        "copper_line_width": 0.19999999999999998,
        "copper_text_italic": false,
        "copper_text_size_h": 1.5,
        "copper_text_size_v": 1.5,
        "copper_text_thickness": 0.3,
        "copper_text_upright": false,
        "courtyard_line_width": 0.049999999999999996,
        "dimension_precision": 4,
        "dimension_units": 3,
        "dimensions": {
          "arrow_length": 1270000,
          "extension_offset": 500000,
          "keep_text_aligned": true,
          "suppress_zeroes": false,
          "text_position": 0,
          "units_format": 1
        },
        "fab_line_width": 0.09999999999999999,
        "fab_text_italic": false,
        "fab_text_size_h": 1.0,
        "fab_text_size_v": 1.0,
        "fab_text_thickness": 0.15,
        "fab_text_upright": false,
        "other_line_width": 0.15,
        "other_text_italic": false,
        "other_text_size_h": 1.0,
        "other_text_size_v": 1.0,
        "other_text_thickness": 0.15,
        "other_text_upright": false,
        "pads": {
          "drill": 0.762,
          "height": 1.524,
          "width": 1.524
        },
        "silk_line_width": 0.15,
        "silk_text_italic": false,
        "silk_text_size_h": 1.0,
        "silk_text_size_v": 1.0,
        "silk_text_thickness": 0.15,
        "silk_text_upright": false,
        "zones": {
          "45_degree_only": false,
          "min_clearance": 0.19999999999999998
        }
      },
      "diff_pair_dimensions": [
        {
          "gap": 0.0,
          "via_gap": 0.0,
          "width": 0.0
        }
      ],
      "drc_exclusions": [],
      "meta": {
        "version": 2
      },
      "rule_severities": {
        "annular_width": "error",
        "clearance": "error",
        "connection_width": "warning",
        "copper_edge_clearance": "error",
        "copper_sliver": "warning",
        "courtyards_overlap": "error",
        "diff_pair_gap_out_of_range": "error",
        "diff_pair_uncoupled_length_too_long": "error",
        "drill_out_of_range": "error",
        "duplicate_footprints": "warning",
        "extra_footprint": "warning",
        "footprint": "error",
        "footprint_type_mismatch": "ignore",
        "hole_clearance": "error",
        "hole_near_hole": "error",
        "invalid_outline": "error",
        "isolated_copper": "warning",
        "item_on_disabled_layer": "error",
        "items_not_allowed": "error",
        "length_out_of_range": "error",
        "lib_footprint_issues": "warning",
        "lib_footprint_mismatch": "warning",
        "malformed_courtyard": "error",
        "microvia_drill_out_of_range": "error",
        "missing_courtyard": "ignore",
        "missing_footprint": "warning",
        "net_conflict": "warning",
        "npth_inside_courtyard": "warning",
        "padstack": "error",
        "pth_inside_courtyard": "warning",
        "shorting_items": "error",
        "silk_edge_clearance": "warning",
        "silk_over_copper": "warning",
        "silk_overlap": "warning",
        "skew_out_of_range": "error",
        "solder_mask_bridge": "error",
        "starved_thermal": "error",
        "text_height": "warning",
        "text_thickness": "warning",
        "through_hole_pad_without_hole": "error",
        "too_many_vias": "error",
        "track_dangling": "warning",
        "track_width": "error",
        "tracks_crossing": "error",
        "unconnected_items": "error",
        "unresolved_variable": "error",
        "via_dangling": "warning",
        "zones_intersect": "error"
      },
      "rules": {
        "allow_blind_buried_vias": false,
        "allow_microvias": false,
        "max_error": 0.005,
        "min_clearance": 0.09999999999999999,
        "min_connection": 0.0,
        "min_copper_edge_clearance": 0.0,
        "min_hole_clearance": 0.08,
        "min_hole_to_hole": 0.25,
        "min_microvia_diameter": 0.19999999999999998,
        "min_microvia_drill": 0.09999999999999999,
        "min_resolved_spokes": 2,
        "min_silk_clearance": 0.0,
        "min_text_height": 0.65,
        "min_text_thickness": 0.08,
        "min_through_hole_diameter": 0.15,
        "min_track_width": 0.09999999999999999,
        "min_via_annular_width": 0.049999999999999996,
        "min_via_diameter": 0.39999999999999997,
        "solder_mask_clearance": 0.0,
        "solder_mask_min_width": 0.0,
        "solder_mask_to_copper_clearance": 0.0,
        "use_height_for_length_calcs": true
      },
      "teardrop_options": [
        {
          "td_allow_use_two_tracks": true,
          "td_curve_segcount": 5,
          "td_on_pad_in_zone": false,
          "td_onpadsmd": true,
          "td_onroundshapesonly": false,
          "td_ontrackend": false,
          "td_onviapad": true
        }
      ],
      "teardrop_parameters": [
        {
          "td_curve_segcount": 0,
          "td_height_ratio": 1.0,
          "td_length_ratio": 0.5,
          "td_maxheight": 2.0,
          "td_maxlen": 1.0,
          "td_target_name": "td_round_shape",
          "td_width_to_size_filter_ratio": 0.9
        },
        {
          "td_curve_segcount": 0,
          "td_height_ratio": 1.0,
          "td_length_ratio": 0.5,
          "td_maxheight": 2.0,
          "td_maxlen": 1.0,
          "td_target_name": "td_rect_shape",
          "td_width_to_size_filter_ratio": 0.9
        },
        {
          "td_curve_segcount": 0,
          "td_height_ratio": 1.0,
          "td_length_ratio": 0.5,
          "td_maxheight": 2.0,
          "td_maxlen": 1.0,
          "td_target_name": "td_track_end",
          "td_width_to_size_filter_ratio": 0.9
        }
      ],
      "track_widths": [
        0.0,
        0.1,
        0.3,
        0.4
      ],
      "via_dimensions": [
        {
          "diameter": 0.0,
          "drill": 0.0
        },
        {
          "diameter": 0.4,
          "drill": 0.15
        },
        {
          "diameter": 0.6,
          "drill": 0.2
        }
      ],
      "zones_allow_external_fillets": false,
      "zones_use_no_outline": true
    },
    "layer_presets": [],
    "viewports": []
  },
  "boards": [],
  "cvpcb": {
    "equivalence_files": []
  },
  "erc": {
    "erc_exclusions": [],
    "meta": {
      "version": 0
    },
    "pin_map": [
      [
        0,
        0,
        0,
        0,
        0,
        0,
        1,
        0,
        0,
        0,
        0,
        2
      ],
      [
        0,
        2,
        0,
        1,
        0,
        0,
        1,
        0,
        2,
        2,
        2,
        2
      ],
      [
        0,
        0,
        0,
        0,
        0,
        0,
        1,
        0,
        1,
        0,
        1,
        2
      ],
      [
        0,
        1,
        0,
        0,
        0,
        0,
        1,
        1,
        2,
        1,
        1,
        2
      ],
      [
        0,
        0,
        0,
        0,
        0,
        0,
        1,
        0,
        0,
        0,
        0,
        2
      ],
      [
        0,
        0,
        0,
        0,
        0,
        0,
        0,
        0,
        0,
        0,
        0,
        2
      ],
      [
        1,
        1,
        1,
        1,
        1,
        0,
        1,
        1,
        1,
        1,
        1,
        2
      ],
      [
        0,
        0,
        0,
        1,
        0,
        0,
        1,
        0,
        0,
        0,
        0,
        2
      ],
      [
        0,
        2,
        1,
        2,
        0,
        0,
        1,
        0,
        2,
        2,
        2,
        2
      ],
      [
        0,
        2,
        0,
        1,
        0,
        0,
        1,
        0,
        2,
        0,
        0,
        2
      ],
      [
        0,
        2,
        1,
        1,
        0,
        0,
        1,
        0,
        2,
        0,
        0,
        2
      ],
      [
        2,
        2,
        2,
        2,
        2,
        2,
        2,
        2,
        2,
        2,
        2,
        2
      ]
    ],
    "rule_severities": {
      "bus_definition_conflict": "error",
      "bus_entry_needed": "error",
      "bus_to_bus_conflict": "error",
      "bus_to_net_conflict": "error",
      "conflicting_netclasses": "error",
      "different_unit_footprint": "error",
      "different_unit_net": "error",
      "duplicate_reference": "error",
      "duplicate_sheet_names": "error",
      "endpoint_off_grid": "warning",
      "extra_units": "error",
      "global_label_dangling": "warning",
      "hier_label_mismatch": "error",
      "label_dangling": "error",
      "lib_symbol_issues": "warning",
      "missing_bidi_pin": "warning",
      "missing_input_pin": "warning",
      "missing_power_pin": "error",
      "missing_unit": "warning",
      "multiple_net_names": "warning",
      "net_not_bus_member": "warning",
      "no_connect_connected": "warning",
      "no_connect_dangling": "warning",
      "pin_not_connected": "error",
      "pin_not_driven": "error",
      "pin_to_pin": "error",
      "power_pin_not_driven": "error",
      "similar_labels": "warning",
      "simulation_model_issue": "ignore",
      "unannotated": "error",
      "unit_value_mismatch": "error",
      "unresolved_variable": "error",
      "wire_dangling": "error"
    }
  },
  "libraries": {
    "pinned_footprint_libs": [],
    "pinned_symbol_libs": []
  },
  "meta": {
    "filename": "antmicro-hdmi-mipi-bridge-hw.kicad_pro",
    "version": 1
  },
  "net_settings": {
    "classes": [
      {
        "bus_width": 12,
        "clearance": 0.1,
        "diff_pair_gap": 0.1,
        "diff_pair_via_gap": 0.25,
        "diff_pair_width": 0.1,
        "line_style": 0,
        "microvia_diameter": 0.3,
        "microvia_drill": 0.1,
        "name": "Default",
        "pcb_color": "rgba(0, 0, 0, 0.000)",
        "schematic_color": "rgba(0, 0, 0, 0.000)",
        "track_width": 0.1,
        "via_diameter": 0.4,
        "via_drill": 0.15,
        "wire_width": 6
      },
      {
        "bus_width": 12,
        "clearance": 0.1,
        "diff_pair_gap": 0.1,
        "diff_pair_via_gap": 0.25,
        "diff_pair_width": 0.1,
        "line_style": 0,
        "microvia_diameter": 0.3,
        "microvia_drill": 0.1,
        "name": "100Ohm-diff-CSI",
        "pcb_color": "rgba(0, 0, 0, 0.000)",
        "schematic_color": "rgba(0, 0, 0, 0.000)",
        "track_width": 0.1,
        "via_diameter": 0.4,
        "via_drill": 0.15,
        "wire_width": 6
      },
      {
        "bus_width": 12,
        "clearance": 0.1,
        "diff_pair_gap": 0.1,
        "diff_pair_via_gap": 0.25,
        "diff_pair_width": 0.1,
        "line_style": 0,
        "microvia_diameter": 0.3,
        "microvia_drill": 0.1,
        "name": "100Ohm-diff-HDMI",
        "pcb_color": "rgba(0, 0, 0, 0.000)",
        "schematic_color": "rgba(0, 0, 0, 0.000)",
        "track_width": 0.1,
        "via_diameter": 0.4,
        "via_drill": 0.15,
        "wire_width": 6
      }
    ],
    "meta": {
      "version": 3
    },
    "net_colors": null,
    "netclass_assignments": null,
    "netclass_patterns": [
      {
        "netclass": "100Ohm-diff-CSI",
        "pattern": "CSI1_CLK_N"
      },
      {
        "netclass": "100Ohm-diff-CSI",
        "pattern": "CSI1_CLK_P"
      },
      {
        "netclass": "100Ohm-diff-CSI",
        "pattern": "CSI1_D1_N"
      },
      {
        "netclass": "100Ohm-diff-CSI",
        "pattern": "CSI1_D1_P"
      },
      {
        "netclass": "100Ohm-diff-CSI",
        "pattern": "CSI1_D2_N"
      },
      {
        "netclass": "100Ohm-diff-CSI",
        "pattern": "CSI1_D2_P"
      },
      {
        "netclass": "100Ohm-diff-CSI",
        "pattern": "CSI1_D3_N"
      },
      {
        "netclass": "100Ohm-diff-CSI",
        "pattern": "CSI1_D3_P"
      },
      {
        "netclass": "100Ohm-diff-CSI",
        "pattern": "CSI1_D4_N"
      },
      {
        "netclass": "100Ohm-diff-CSI",
        "pattern": "CSI1_D4_P"
      },
      {
        "netclass": "100Ohm-diff-CSI",
        "pattern": "CSI3_CLK_N"
      },
      {
        "netclass": "100Ohm-diff-CSI",
        "pattern": "CSI3_CLK_P"
      },
      {
        "netclass": "100Ohm-diff-CSI",
        "pattern": "CSI3_D1_N"
      },
      {
        "netclass": "100Ohm-diff-CSI",
        "pattern": "CSI3_D1_P"
      },
      {
        "netclass": "100Ohm-diff-CSI",
        "pattern": "CSI3_D2_N"
      },
      {
        "netclass": "100Ohm-diff-CSI",
        "pattern": "CSI3_D2_P"
      },
      {
        "netclass": "100Ohm-diff-CSI",
        "pattern": "CSI3_D3_N"
      },
      {
        "netclass": "100Ohm-diff-CSI",
        "pattern": "CSI3_D3_P"
      },
      {
        "netclass": "100Ohm-diff-CSI",
        "pattern": "CSI3_D4_N"
      },
      {
        "netclass": "100Ohm-diff-CSI",
        "pattern": "CSI3_D4_P"
      },
      {
        "netclass": "100Ohm-diff-HDMI",
        "pattern": "/Channel 1/HDMI1_CLK_N"
      },
      {
        "netclass": "100Ohm-diff-HDMI",
        "pattern": "/Channel 1/HDMI1_CLK_P"
      },
      {
        "netclass": "100Ohm-diff-HDMI",
        "pattern": "/Channel 1/HDMI1_D0_N"
      },
      {
        "netclass": "100Ohm-diff-HDMI",
        "pattern": "/Channel 1/HDMI1_D0_P"
      },
      {
        "netclass": "100Ohm-diff-HDMI",
        "pattern": "/Channel 1/HDMI1_D1_N"
      },
      {
        "netclass": "100Ohm-diff-HDMI",
        "pattern": "/Channel 1/HDMI1_D1_P"
      },
      {
        "netclass": "100Ohm-diff-HDMI",
        "pattern": "/Channel 1/HDMI1_D2_N"
      },
      {
        "netclass": "100Ohm-diff-HDMI",
        "pattern": "/Channel 1/HDMI1_D2_P"
      },
      {
        "netclass": "100Ohm-diff-HDMI",
        "pattern": "/Channel 2/HDMI2_CLK_P"
      },
      {
        "netclass": "100Ohm-diff-HDMI",
        "pattern": "/Channel 2/HDMI2_D0_N"
      },
      {
        "netclass": "100Ohm-diff-HDMI",
        "pattern": "/Channel 2/HDMI2_D0_P"
      },
      {
        "netclass": "100Ohm-diff-HDMI",
        "pattern": "/Channel 2/HDMI2_D1_N"
      },
      {
        "netclass": "100Ohm-diff-HDMI",
        "pattern": "/Channel 2/HDMI2_D1_P"
      },
      {
        "netclass": "100Ohm-diff-HDMI",
        "pattern": "/Channel 2/HDMI2_D2_N"
      },
      {
        "netclass": "100Ohm-diff-HDMI",
        "pattern": "/Channel 2/HDMI2_D2_P"
      }
    ]
  },
  "pcbnew": {
    "last_paths": {
      "gencad": "",
      "idf": "",
      "netlist": "",
      "specctra_dsn": "",
      "step": "",
      "vrml": ""
    },
    "page_layout_descr_file": ""
  },
  "schematic": {
    "annotate_start_num": 0,
    "drawing": {
      "dashed_lines_dash_length_ratio": 12.0,
      "dashed_lines_gap_length_ratio": 3.0,
      "default_line_thickness": 6.0,
      "default_text_size": 50.0,
      "field_names": [],
      "intersheets_ref_own_page": false,
      "intersheets_ref_prefix": "",
      "intersheets_ref_short": false,
      "intersheets_ref_show": false,
      "intersheets_ref_suffix": "",
      "junction_size_choice": 3,
      "label_size_ratio": 0.375,
      "pin_symbol_size": 25.0,
      "text_offset_ratio": 0.15
    },
    "legacy_lib_dir": "",
    "legacy_lib_list": [],
    "meta": {
      "version": 1
    },
    "net_format_name": "",
    "ngspice": {
      "fix_include_paths": true,
      "fix_passive_vals": false,
      "meta": {
        "version": 0
      },
      "model_mode": 0,
      "workbook_filename": ""
    },
    "page_layout_descr_file": "",
    "plot_directory": "",
    "spice_adjust_passive_values": false,
    "spice_current_sheet_as_root": false,
    "spice_external_command": "spice \"%I\"",
    "spice_model_current_sheet_as_root": true,
    "spice_save_all_currents": false,
    "spice_save_all_voltages": false,
    "subpart_first_id": 65,
    "subpart_id_separator": 0
  },
  "sheets": [
    [
      "",
      ""
    ],
    [
      "",
      "Channel 1"
    ],
    [
      "",
      "Channel 2"
    ],
    [
      "",
      "CSI"
    ]
  ],
  "text_variables": {}
}
